(kicad_pcb
	(version 20260206)
	(generator "pcbnew")
	(generator_version "10.0")
	(general
		(thickness 1.6)
		(legacy_teardrops no)
	)
	(paper "A4")
	(title_block
		(title "Bryce Canyon_IOM_M2_16342-2_OCP.brd")
		(comment 1 "Bryce Canyon / footprints 84-90 of 1146")
	)
	(layers
		(0 "F.Cu" signal "TOP")
		(4 "In1.Cu" signal "L2GND")
		(6 "In2.Cu" signal "L3")
		(8 "In3.Cu" signal "L4VCC")
		(10 "In4.Cu" signal "L5VCC")
		(12 "In5.Cu" signal "L6")
		(14 "In6.Cu" signal "L7GND")
		(2 "B.Cu" signal "BOTTOM")
		(9 "F.Adhes" user "F.Adhesive")
		(11 "B.Adhes" user "B.Adhesive")
		(13 "F.Paste" user "Package Geometry/Pastemask Top")
		(15 "B.Paste" user "Package Geometry/Pastemask Bottom")
		(5 "F.SilkS" user "Ref Des/Silkscreen Top")
		(7 "B.SilkS" user "Ref Des/Silkscreen Bottom")
		(1 "F.Mask" user "Board Geometry/Soldermask Top")
		(3 "B.Mask" user "Board Geometry/Soldermask Bottom")
		(17 "Dwgs.User" user "User.Drawings")
		(19 "Cmts.User" user "User.Comments")
		(21 "Eco1.User" user "User.Eco1")
		(23 "Eco2.User" user "User.Eco2")
		(25 "Edge.Cuts" user "Board Geometry/Outline")
		(27 "Margin" user)
		(31 "F.CrtYd" user "Package Geometry/Place Bound Top")
		(29 "B.CrtYd" user "Package Geometry/Place Bound Bottom")
		(35 "F.Fab" user "Ref Des/Assembly Top")
		(33 "B.Fab" user "Ref Des/Assembly Bottom")
	)
	(footprint ""
		(layer "F.Cu")
		(at 225.880168 -53.12029 90)
		(property "Reference" "C151"
			(at 0 0 90)
			(layer "F.SilkS")
			(hide yes)
			(effects
				(font
					(size 1.27 1.27)
				)
			)
		)
		(property "Value" "SC10U16V5KX-7-GP-U"
			(at -0.0762 -6.1214 90)
			(unlocked yes)
			(layer "F.Fab")
			(hide yes)
			(effects
				(font
					(size 1.016 1.016)
					(thickness 0.1524)
				)
			)
		)
		(property "Device Type" "C805H58"
			(at -0.0762 -8.1534 90)
			(unlocked yes)
			(layer "F.Fab")
			(hide yes)
			(effects
				(font
					(size 1.016 1.016)
					(thickness 0.1524)
				)
			)
		)
		(duplicate_pad_numbers_are_jumpers no)
		(fp_line
			(start 0.635 0)
			(end -0.635 0)
			(stroke
				(width 0.508)
				(type default)
			)
			(layer "F.SilkS")
		)
		(fp_rect
			(start -0.9652 1.778)
			(end 0.9652 -1.778)
			(stroke
				(width 0)
				(type default)
			)
			(fill no)
			(layer "F.CrtYd")
		)
		(fp_poly
			(pts
				(xy -0.9652 -1.778) (xy 0.9652 -1.778) (xy 0.9652 1.778) (xy -0.9652 1.778)
			)
			(stroke
				(width 0)
				(type default)
			)
			(fill no)
			(layer "F.Fab")
		)
		(pad "1" smd rect
			(at 0 -0.9652 90)
			(size 1.397 1.143)
			(layers "F.Cu" "F.Mask" "F.Paste")
			(net "P12V_STBY_VIN_PU1")
		)
		(pad "2" smd rect
			(at 0 0.9652 90)
			(size 1.397 1.143)
			(layers "F.Cu" "F.Mask" "F.Paste")
			(net "GND")
		)
	)
	(footprint ""
		(layer "F.Cu")
		(at 34.284158 -155.71724 -90)
		(property "Reference" "R322"
			(at 0 0 270)
			(layer "F.SilkS")
			(hide yes)
			(effects
				(font
					(size 1.27 1.27)
				)
			)
		)
		(property "Value" "0R2J-2-GP"
			(at 0.064008 -3.993896 270)
			(unlocked yes)
			(layer "F.Fab")
			(hide yes)
			(effects
				(font
					(size 1.016 1.016)
					(thickness 0.1524)
				)
			)
		)
		(property "Device Type" "R402H16"
			(at 0.064008 -5.517896 270)
			(unlocked yes)
			(layer "F.Fab")
			(hide yes)
			(effects
				(font
					(size 1.016 1.016)
					(thickness 0.1524)
				)
			)
		)
		(duplicate_pad_numbers_are_jumpers no)
		(fp_line
			(start -0.508 -0.9398)
			(end -0.508 0.9398)
			(stroke
				(width 0.1524)
				(type default)
			)
			(layer "F.SilkS")
		)
		(fp_line
			(start 0.508 -0.9398)
			(end -0.508 -0.9398)
			(stroke
				(width 0.1524)
				(type default)
			)
			(layer "F.SilkS")
		)
		(fp_rect
			(start -0.508 0.9398)
			(end 0.508 -0.9398)
			(stroke
				(width 0)
				(type default)
			)
			(fill no)
			(layer "F.CrtYd")
		)
		(fp_rect
			(start -0.508 0.9398)
			(end 0.508 -0.9398)
			(stroke
				(width 0)
				(type default)
			)
			(fill no)
			(layer "F.Fab")
		)
		(pad "1" smd custom
			(at 0 -0.4445 270)
			(size 0.1397 0.1397)
			(layers "F.Cu" "F.Mask" "F.Paste")
			(net "COMP_POWER_FAIL_R_N")
			(options
				(clearance outline)
				(anchor circle)
			)
			(primitives
				(gr_poly
					(pts
						(arc
							(start -0.1778 -0.2794)
							(mid -0.249642 -0.249642)
							(end -0.2794 -0.1778)
						)
						(arc
							(start -0.2794 0.1778)
							(mid -0.249642 0.249642)
							(end -0.1778 0.2794)
						)
						(arc
							(start 0.1778 0.2794)
							(mid 0.249642 0.249642)
							(end 0.2794 0.1778)
						)
						(arc
							(start 0.2794 -0.1778)
							(mid 0.249642 -0.249642)
							(end 0.1778 -0.2794)
						)
					)
					(width 0)
					(fill yes)
				)
			)
		)
		(pad "2" smd custom
			(at 0 0.4445 270)
			(size 0.1397 0.1397)
			(layers "F.Cu" "F.Mask" "F.Paste")
			(net "COMP_POWER_FAIL_N")
			(options
				(clearance outline)
				(anchor circle)
			)
			(primitives
				(gr_poly
					(pts
						(arc
							(start -0.1778 -0.2794)
							(mid -0.249642 -0.249642)
							(end -0.2794 -0.1778)
						)
						(arc
							(start -0.2794 0.1778)
							(mid -0.249642 0.249642)
							(end -0.1778 0.2794)
						)
						(arc
							(start 0.1778 0.2794)
							(mid 0.249642 0.249642)
							(end 0.2794 0.1778)
						)
						(arc
							(start 0.2794 -0.1778)
							(mid 0.249642 -0.249642)
							(end 0.1778 -0.2794)
						)
					)
					(width 0)
					(fill yes)
				)
			)
		)
	)
	(footprint ""
		(layer "F.Cu")
		(at 36.900866 -157.70098)
		(property "Reference" "R714"
			(at 0 0 0)
			(layer "F.SilkS")
			(hide yes)
			(effects
				(font
					(size 1.27 1.27)
				)
			)
		)
		(property "Value" "0R2J-2-GP"
			(at 0.064008 -3.993896 0)
			(unlocked yes)
			(layer "F.Fab")
			(hide yes)
			(effects
				(font
					(size 1.016 1.016)
					(thickness 0.1524)
				)
			)
		)
		(property "Device Type" "R402H16"
			(at 0.064008 -5.517896 0)
			(unlocked yes)
			(layer "F.Fab")
			(hide yes)
			(effects
				(font
					(size 1.016 1.016)
					(thickness 0.1524)
				)
			)
		)
		(duplicate_pad_numbers_are_jumpers no)
		(fp_line
			(start -0.508 -0.9398)
			(end -0.508 0.9398)
			(stroke
				(width 0.1524)
				(type default)
			)
			(layer "F.SilkS")
		)
		(fp_line
			(start 0.508 -0.9398)
			(end -0.508 -0.9398)
			(stroke
				(width 0.1524)
				(type default)
			)
			(layer "F.SilkS")
		)
		(fp_rect
			(start -0.508 0.9398)
			(end 0.508 -0.9398)
			(stroke
				(width 0)
				(type default)
			)
			(fill no)
			(layer "F.CrtYd")
		)
		(fp_rect
			(start -0.508 0.9398)
			(end 0.508 -0.9398)
			(stroke
				(width 0)
				(type default)
			)
			(fill no)
			(layer "F.Fab")
		)
		(pad "1" smd custom
			(at 0 -0.4445)
			(size 0.1397 0.1397)
			(layers "F.Cu" "F.Mask" "F.Paste")
			(net "PWM_OUT_ZONE_D")
			(options
				(clearance outline)
				(anchor circle)
			)
			(primitives
				(gr_poly
					(pts
						(arc
							(start -0.1778 -0.2794)
							(mid -0.249642 -0.249642)
							(end -0.2794 -0.1778)
						)
						(arc
							(start -0.2794 0.1778)
							(mid -0.249642 0.249642)
							(end -0.1778 0.2794)
						)
						(arc
							(start 0.1778 0.2794)
							(mid 0.249642 0.249642)
							(end 0.2794 0.1778)
						)
						(arc
							(start 0.2794 -0.1778)
							(mid 0.249642 -0.249642)
							(end 0.1778 -0.2794)
						)
					)
					(width 0)
					(fill yes)
				)
			)
		)
		(pad "2" smd custom
			(at 0 0.4445)
			(size 0.1397 0.1397)
			(layers "F.Cu" "F.Mask" "F.Paste")
			(net "FAN_PWM1_BMC")
			(options
				(clearance outline)
				(anchor circle)
			)
			(primitives
				(gr_poly
					(pts
						(arc
							(start -0.1778 -0.2794)
							(mid -0.249642 -0.249642)
							(end -0.2794 -0.1778)
						)
						(arc
							(start -0.2794 0.1778)
							(mid -0.249642 0.249642)
							(end -0.1778 0.2794)
						)
						(arc
							(start 0.1778 0.2794)
							(mid 0.249642 0.249642)
							(end 0.2794 0.1778)
						)
						(arc
							(start 0.2794 -0.1778)
							(mid 0.249642 -0.249642)
							(end 0.1778 -0.2794)
						)
					)
					(width 0)
					(fill yes)
				)
			)
		)
	)
	(footprint ""
		(layer "F.Cu")
		(at 76.9874 -167.59682 180)
		(property "Reference" "C524"
			(at 0 0 180)
			(layer "F.SilkS")
			(hide yes)
			(effects
				(font
					(size 1.27 1.27)
				)
			)
		)
		(property "Value" "SC1U16V2KX-7-GP"
			(at 1.7526 -1.6002 180)
			(unlocked yes)
			(layer "F.Fab")
			(hide yes)
			(effects
				(font
					(size 1.016 1.016)
					(thickness 0.1524)
				)
			)
		)
		(property "Device Type" "C402-TO0D2H24"
			(at 1.7526 -3.1242 180)
			(unlocked yes)
			(layer "F.Fab")
			(hide yes)
			(effects
				(font
					(size 1.016 1.016)
					(thickness 0.1524)
				)
			)
		)
		(duplicate_pad_numbers_are_jumpers no)
		(fp_rect
			(start -0.4826 0.889)
			(end 0.4826 -0.889)
			(stroke
				(width 0)
				(type default)
			)
			(fill no)
			(layer "F.CrtYd")
		)
		(fp_rect
			(start -0.4826 0.889)
			(end 0.4826 -0.889)
			(stroke
				(width 0)
				(type default)
			)
			(fill no)
			(layer "F.Fab")
		)
		(pad "1" smd custom
			(at 0 -0.4572 180)
			(size 0.1524 0.1524)
			(layers "F.Cu" "F.Mask" "F.Paste")
			(net "P1V15_STBY_PG")
			(options
				(clearance outline)
				(anchor circle)
			)
			(primitives
				(gr_poly
					(pts
						(arc
							(start -0.254 0.3048)
							(mid -0.325842 0.275042)
							(end -0.3556 0.2032)
						)
						(arc
							(start -0.3556 -0.2032)
							(mid -0.325842 -0.275042)
							(end -0.254 -0.3048)
						)
						(arc
							(start 0.254 -0.3048)
							(mid 0.325842 -0.275042)
							(end 0.3556 -0.2032)
						)
						(arc
							(start 0.3556 0.2032)
							(mid 0.325842 0.275042)
							(end 0.254 0.3048)
						)
					)
					(width 0)
					(fill yes)
				)
			)
		)
		(pad "2" smd custom
			(at 0 0.4572 180)
			(size 0.1524 0.1524)
			(layers "F.Cu" "F.Mask" "F.Paste")
			(net "GND")
			(options
				(clearance outline)
				(anchor circle)
			)
			(primitives
				(gr_poly
					(pts
						(arc
							(start -0.254 0.3048)
							(mid -0.325842 0.275042)
							(end -0.3556 0.2032)
						)
						(arc
							(start -0.3556 -0.2032)
							(mid -0.325842 -0.275042)
							(end -0.254 -0.3048)
						)
						(arc
							(start 0.254 -0.3048)
							(mid 0.325842 -0.275042)
							(end 0.3556 -0.2032)
						)
						(arc
							(start 0.3556 0.2032)
							(mid 0.325842 0.275042)
							(end 0.254 0.3048)
						)
					)
					(width 0)
					(fill yes)
				)
			)
		)
	)
	(footprint ""
		(layer "F.Cu")
		(at 27.502358 -145.377154)
		(property "Reference" "R219"
			(at 0 0 0)
			(layer "F.SilkS")
			(hide yes)
			(effects
				(font
					(size 1.27 1.27)
				)
			)
		)
		(property "Value" "240R2F-1-GP"
			(at 0.064008 -3.993896 0)
			(unlocked yes)
			(layer "F.Fab")
			(hide yes)
			(effects
				(font
					(size 1.016 1.016)
					(thickness 0.1524)
				)
			)
		)
		(property "Device Type" "R402H16"
			(at 0.064008 -5.517896 0)
			(unlocked yes)
			(layer "F.Fab")
			(hide yes)
			(effects
				(font
					(size 1.016 1.016)
					(thickness 0.1524)
				)
			)
		)
		(duplicate_pad_numbers_are_jumpers no)
		(fp_line
			(start -0.508 -0.9398)
			(end -0.508 0.9398)
			(stroke
				(width 0.1524)
				(type default)
			)
			(layer "F.SilkS")
		)
		(fp_line
			(start 0.508 -0.9398)
			(end -0.508 -0.9398)
			(stroke
				(width 0.1524)
				(type default)
			)
			(layer "F.SilkS")
		)
		(fp_rect
			(start -0.508 0.9398)
			(end 0.508 -0.9398)
			(stroke
				(width 0)
				(type default)
			)
			(fill no)
			(layer "F.CrtYd")
		)
		(fp_rect
			(start -0.508 0.9398)
			(end 0.508 -0.9398)
			(stroke
				(width 0)
				(type default)
			)
			(fill no)
			(layer "F.Fab")
		)
		(pad "1" smd custom
			(at 0 -0.4445)
			(size 0.1397 0.1397)
			(layers "F.Cu" "F.Mask" "F.Paste")
			(net "GND")
			(options
				(clearance outline)
				(anchor circle)
			)
			(primitives
				(gr_poly
					(pts
						(arc
							(start -0.1778 -0.2794)
							(mid -0.249642 -0.249642)
							(end -0.2794 -0.1778)
						)
						(arc
							(start -0.2794 0.1778)
							(mid -0.249642 0.249642)
							(end -0.1778 0.2794)
						)
						(arc
							(start 0.1778 0.2794)
							(mid 0.249642 0.249642)
							(end 0.2794 0.1778)
						)
						(arc
							(start 0.2794 -0.1778)
							(mid 0.249642 -0.249642)
							(end 0.1778 -0.2794)
						)
					)
					(width 0)
					(fill yes)
				)
			)
		)
		(pad "2" smd custom
			(at 0 0.4445)
			(size 0.1397 0.1397)
			(layers "F.Cu" "F.Mask" "F.Paste")
			(net "PD_ZQ")
			(options
				(clearance outline)
				(anchor circle)
			)
			(primitives
				(gr_poly
					(pts
						(arc
							(start -0.1778 -0.2794)
							(mid -0.249642 -0.249642)
							(end -0.2794 -0.1778)
						)
						(arc
							(start -0.2794 0.1778)
							(mid -0.249642 0.249642)
							(end -0.1778 0.2794)
						)
						(arc
							(start 0.1778 0.2794)
							(mid 0.249642 0.249642)
							(end 0.2794 0.1778)
						)
						(arc
							(start 0.2794 -0.1778)
							(mid 0.249642 -0.249642)
							(end 0.1778 -0.2794)
						)
					)
					(width 0)
					(fill yes)
				)
			)
		)
	)
	(footprint ""
		(layer "F.Cu")
		(at 88.844628 -65.475612 90)
		(property "Reference" "R9"
			(at 0 0 90)
			(layer "F.SilkS")
			(hide yes)
			(effects
				(font
					(size 1.27 1.27)
				)
			)
		)
		(property "Value" "0R2J-2-GP"
			(at 0.064008 -3.993896 90)
			(unlocked yes)
			(layer "F.Fab")
			(hide yes)
			(effects
				(font
					(size 1.016 1.016)
					(thickness 0.1524)
				)
			)
		)
		(property "Device Type" "R402H16"
			(at 0.064008 -5.517896 90)
			(unlocked yes)
			(layer "F.Fab")
			(hide yes)
			(effects
				(font
					(size 1.016 1.016)
					(thickness 0.1524)
				)
			)
		)
		(duplicate_pad_numbers_are_jumpers no)
		(fp_line
			(start 0.508 -0.9398)
			(end -0.508 -0.9398)
			(stroke
				(width 0.1524)
				(type default)
			)
			(layer "F.SilkS")
		)
		(fp_line
			(start -0.508 -0.9398)
			(end -0.508 0.9398)
			(stroke
				(width 0.1524)
				(type default)
			)
			(layer "F.SilkS")
		)
		(fp_rect
			(start -0.508 0.9398)
			(end 0.508 -0.9398)
			(stroke
				(width 0)
				(type default)
			)
			(fill no)
			(layer "F.CrtYd")
		)
		(fp_rect
			(start -0.508 0.9398)
			(end 0.508 -0.9398)
			(stroke
				(width 0)
				(type default)
			)
			(fill no)
			(layer "F.Fab")
		)
		(pad "1" smd custom
			(at 0 -0.4445 90)
			(size 0.1397 0.1397)
			(layers "F.Cu" "F.Mask" "F.Paste")
			(net "NCSI_RX_ER_R")
			(options
				(clearance outline)
				(anchor circle)
			)
			(primitives
				(gr_poly
					(pts
						(arc
							(start -0.1778 -0.2794)
							(mid -0.249642 -0.249642)
							(end -0.2794 -0.1778)
						)
						(arc
							(start -0.2794 0.1778)
							(mid -0.249642 0.249642)
							(end -0.1778 0.2794)
						)
						(arc
							(start 0.1778 0.2794)
							(mid 0.249642 0.249642)
							(end 0.2794 0.1778)
						)
						(arc
							(start 0.2794 -0.1778)
							(mid 0.249642 -0.249642)
							(end 0.1778 -0.2794)
						)
					)
					(width 0)
					(fill yes)
				)
			)
		)
		(pad "2" smd custom
			(at 0 0.4445 90)
			(size 0.1397 0.1397)
			(layers "F.Cu" "F.Mask" "F.Paste")
			(net "NCSI_RX_ER")
			(options
				(clearance outline)
				(anchor circle)
			)
			(primitives
				(gr_poly
					(pts
						(arc
							(start -0.1778 -0.2794)
							(mid -0.249642 -0.249642)
							(end -0.2794 -0.1778)
						)
						(arc
							(start -0.2794 0.1778)
							(mid -0.249642 0.249642)
							(end -0.1778 0.2794)
						)
						(arc
							(start 0.1778 0.2794)
							(mid 0.249642 0.249642)
							(end 0.2794 0.1778)
						)
						(arc
							(start 0.2794 -0.1778)
							(mid 0.249642 -0.249642)
							(end 0.1778 -0.2794)
						)
					)
					(width 0)
					(fill yes)
				)
			)
		)
	)
	(footprint ""
		(layer "F.Cu")
		(at 69.596762 -178.901598 90)
		(property "Reference" "C196"
			(at 0 0 90)
			(layer "F.SilkS")
			(hide yes)
			(effects
				(font
					(size 1.27 1.27)
				)
			)
		)
		(property "Value" "SC470P50V2KX-3GP"
			(at 1.1811 -2.7051 90)
			(unlocked yes)
			(layer "F.Fab")
			(hide yes)
			(effects
				(font
					(size 1.016 1.016)
					(thickness 0.1524)
				)
			)
		)
		(property "Device Type" "C402H22"
			(at 1.1811 -4.2291 90)
			(unlocked yes)
			(layer "F.Fab")
			(hide yes)
			(effects
				(font
					(size 1.016 1.016)
					(thickness 0.1524)
				)
			)
		)
		(duplicate_pad_numbers_are_jumpers no)
		(fp_rect
			(start -0.4318 0.9525)
			(end 0.4318 -0.9525)
			(stroke
				(width 0)
				(type default)
			)
			(fill no)
			(layer "F.CrtYd")
		)
		(fp_rect
			(start -0.4318 0.9525)
			(end 0.4318 -0.9525)
			(stroke
				(width 0)
				(type default)
			)
			(fill no)
			(layer "F.Fab")
		)
		(pad "1" smd custom
			(at 0 -0.4445 90)
			(size 0.1524 0.1524)
			(layers "F.Cu" "F.Mask" "F.Paste")
			(net "GND")
			(options
				(clearance outline)
				(anchor circle)
			)
			(primitives
				(gr_poly
					(pts
						(arc
							(start 0.3048 -0.2032)
							(mid 0.275042 -0.275042)
							(end 0.2032 -0.3048)
						)
						(arc
							(start -0.2032 -0.3048)
							(mid -0.275042 -0.275042)
							(end -0.3048 -0.2032)
						)
						(arc
							(start -0.3048 0.2032)
							(mid -0.275042 0.275042)
							(end -0.2032 0.3048)
						)
						(arc
							(start 0.2032 0.3048)
							(mid 0.275042 0.275042)
							(end 0.3048 0.2032)
						)
					)
					(width 0)
					(fill yes)
				)
			)
		)
		(pad "2" smd custom
			(at 0 0.4445 90)
			(size 0.1524 0.1524)
			(layers "F.Cu" "F.Mask" "F.Paste")
			(net "TPS74801_P2V5_STBY_SS")
			(options
				(clearance outline)
				(anchor circle)
			)
			(primitives
				(gr_poly
					(pts
						(arc
							(start 0.3048 -0.2032)
							(mid 0.275042 -0.275042)
							(end 0.2032 -0.3048)
						)
						(arc
							(start -0.2032 -0.3048)
							(mid -0.275042 -0.275042)
							(end -0.3048 -0.2032)
						)
						(arc
							(start -0.3048 0.2032)
							(mid -0.275042 0.275042)
							(end -0.2032 0.3048)
						)
						(arc
							(start 0.2032 0.3048)
							(mid 0.275042 0.275042)
							(end 0.3048 0.2032)
						)
					)
					(width 0)
					(fill yes)
				)
			)
		)
	)
)
